(kicad_pcb
	(version 20241229)
	(generator "pcbnew")
	(generator_version "9.0")
	(general
		(thickness 1.62)
		(legacy_teardrops no)
	)
	(paper "A4")
	(title_block
		(title "OCuLink to 10GbE adapter")
		(date "2026-02-23")
		(rev "1.1.0")
		(company "Antmicro Ltd")
		(comment 1 "www.antmicro.com")
		(comment 9 "footprints 18-23 of 510")
	)
	(layers
		(0 "F.Cu" signal)
		(4 "In1.Cu" signal)
		(6 "In2.Cu" signal)
		(8 "In3.Cu" signal)
		(10 "In4.Cu" signal)
		(12 "In5.Cu" signal)
		(14 "In6.Cu" signal)
		(2 "B.Cu" signal)
		(9 "F.Adhes" user "F.Adhesive")
		(11 "B.Adhes" user "B.Adhesive")
		(13 "F.Paste" user)
		(15 "B.Paste" user)
		(5 "F.SilkS" user "F.Silkscreen")
		(7 "B.SilkS" user "B.Silkscreen")
		(1 "F.Mask" user)
		(3 "B.Mask" user)
		(17 "Dwgs.User" user "User.Drawings")
		(19 "Cmts.User" user "User.Comments")
		(21 "Eco1.User" user "User.Eco1")
		(23 "Eco2.User" user "User.Eco2")
		(25 "Edge.Cuts" user)
		(27 "Margin" user)
		(31 "F.CrtYd" user "F.Courtyard")
		(29 "B.CrtYd" user "B.Courtyard")
		(35 "F.Fab" user)
		(33 "B.Fab" user)
	)
	(footprint "antmicro-footprints:R_0603_1608Metric"
		(layer "F.Cu")
		(at 63.2 107.2)
		(descr "Resistor SMD 0603")
		(tags "resistor SMD 0603")
		(property "Reference" "R19"
			(at -0.16 -1.41 0)
			(layer "F.SilkS")
			(effects
				(font
					(size 0.7 0.7)
					(thickness 0.15)
				)
				(justify left bottom)
			)
		)
		(property "Value" "R_0R_22.4A_0603"
			(at 0 1.6 0)
			(layer "F.Fab")
			(hide yes)
			(effects
				(font
					(size 0.7 0.7)
					(thickness 0.15)
				)
				(justify left bottom)
			)
		)
		(property "Datasheet" "https://fscdn.rohm.com/en/products/databook/datasheet/passive/resistor/chip_resistor/pmr-jpw-e.pdf"
			(at 0 0 0)
			(layer "F.Fab")
			(hide yes)
			(effects
				(font
					(size 1.27 1.27)
					(thickness 0.15)
				)
			)
		)
		(property "Description" "SMD Chip Resistor"
			(at 0 0 0)
			(layer "F.Fab")
			(hide yes)
			(effects
				(font
					(size 1.27 1.27)
					(thickness 0.15)
				)
			)
		)
		(property "MPN" "PMR03EZPJ000"
			(at 0 0 0)
			(unlocked yes)
			(layer "F.Fab")
			(hide yes)
			(effects
				(font
					(size 1 1)
					(thickness 0.15)
				)
			)
		)
		(property "Manufacturer" "ROHM Semiconductor"
			(at 0 0 0)
			(unlocked yes)
			(layer "F.Fab")
			(hide yes)
			(effects
				(font
					(size 1 1)
					(thickness 0.15)
				)
			)
		)
		(property "Val" "0R"
			(at 0 0 0)
			(unlocked yes)
			(layer "F.Fab")
			(hide yes)
			(effects
				(font
					(size 1 1)
					(thickness 0.15)
				)
			)
		)
		(property "Max. Curr." "22.4A"
			(at 0 0 0)
			(unlocked yes)
			(layer "F.Fab")
			(hide yes)
			(effects
				(font
					(size 1 1)
					(thickness 0.15)
				)
			)
		)
		(property "Author" "Antmicro"
			(at 0 0 0)
			(unlocked yes)
			(layer "F.Fab")
			(hide yes)
			(effects
				(font
					(size 1 1)
					(thickness 0.15)
				)
			)
		)
		(property "License" "Apache-2.0"
			(at 0 0 0)
			(unlocked yes)
			(layer "F.Fab")
			(hide yes)
			(effects
				(font
					(size 1 1)
					(thickness 0.15)
				)
			)
		)
		(property "Tolerance" "template_tolerance"
			(at 0 0 0)
			(unlocked yes)
			(layer "F.Fab")
			(hide yes)
			(effects
				(font
					(size 1 1)
					(thickness 0.15)
				)
			)
		)
		(sheetname "/Power/")
		(sheetfile "power.kicad_sch")
		(attr smd)
		(fp_line
			(start -0.15 -0.4)
			(end 0.15 -0.4)
			(stroke
				(width 0.15)
				(type solid)
			)
			(layer "F.SilkS")
		)
		(fp_line
			(start -0.15 0.4)
			(end 0.15 0.4)
			(stroke
				(width 0.15)
				(type solid)
			)
			(layer "F.SilkS")
		)
		(fp_rect
			(start -1.25 -0.65)
			(end 1.25 0.65)
			(stroke
				(width 0.05)
				(type solid)
			)
			(fill no)
			(layer "F.CrtYd")
		)
		(fp_rect
			(start -0.8 -0.4)
			(end 0.8 0.4)
			(stroke
				(width 0.15)
				(type solid)
			)
			(fill no)
			(layer "F.Fab")
		)
		(pad "1" smd roundrect
			(at -0.7 0)
			(size 0.8 1)
			(layers "F.Cu" "F.Mask" "F.Paste")
			(roundrect_rratio 0.2)
			(net 312 "/Power/+1V0_OUT")
			(pintype "passive")
		)
		(pad "2" smd roundrect
			(at 0.7 0)
			(size 0.8 1)
			(layers "F.Cu" "F.Mask" "F.Paste")
			(roundrect_rratio 0.2)
			(net 302 "+1V0")
			(pintype "passive")
		)
	)
	(footprint "antmicro-footprints:C_0603_1608Metric_EIA"
		(layer "F.Cu")
		(at 60.649999 100.850001)
		(descr "Capacitor SMD 0603, IPC-7351 Density Level A")
		(tags "Capacitor 0603")
		(property "Reference" "C206"
			(at -4.039999 -1.140001 0)
			(layer "F.SilkS")
			(effects
				(font
					(size 0.7 0.7)
					(thickness 0.15)
				)
				(justify left bottom)
			)
		)
		(property "Value" "C_22u_16V_0603"
			(at -1.42757 1.770288 0)
			(layer "F.Fab")
			(hide yes)
			(effects
				(font
					(size 0.7 0.7)
					(thickness 0.15)
				)
				(justify left bottom)
			)
		)
		(property "Datasheet" "https://product.samsungsem.com/mlcc/CL10A226MO7JZN.do"
			(at 0 0 0)
			(layer "F.Fab")
			(hide yes)
			(effects
				(font
					(size 1.27 1.27)
					(thickness 0.15)
				)
			)
		)
		(property "Description" "SMD Multilayer Ceramic Capacitor"
			(at 0 0 0)
			(layer "F.Fab")
			(hide yes)
			(effects
				(font
					(size 1.27 1.27)
					(thickness 0.15)
				)
			)
		)
		(property "MPN" "CL10A226MO7JZNC"
			(at 0 0 0)
			(unlocked yes)
			(layer "F.Fab")
			(hide yes)
			(effects
				(font
					(size 1 1)
					(thickness 0.15)
				)
			)
		)
		(property "Manufacturer" "Samsung Electro-Mechanics"
			(at 0 0 0)
			(unlocked yes)
			(layer "F.Fab")
			(hide yes)
			(effects
				(font
					(size 1 1)
					(thickness 0.15)
				)
			)
		)
		(property "License" "Apache-2.0"
			(at 0 0 0)
			(unlocked yes)
			(layer "F.Fab")
			(hide yes)
			(effects
				(font
					(size 1 1)
					(thickness 0.15)
				)
			)
		)
		(property "Author" "Antmicro"
			(at 0 0 0)
			(unlocked yes)
			(layer "F.Fab")
			(hide yes)
			(effects
				(font
					(size 1 1)
					(thickness 0.15)
				)
			)
		)
		(property "Val" "22u"
			(at 0 0 0)
			(unlocked yes)
			(layer "F.Fab")
			(hide yes)
			(effects
				(font
					(size 1 1)
					(thickness 0.15)
				)
			)
		)
		(property "Voltage" "16V"
			(at 0 0 0)
			(unlocked yes)
			(layer "F.Fab")
			(hide yes)
			(effects
				(font
					(size 1 1)
					(thickness 0.15)
				)
			)
		)
		(property "Dielectric" ""
			(at 0 0 0)
			(unlocked yes)
			(layer "F.Fab")
			(hide yes)
			(effects
				(font
					(size 1 1)
					(thickness 0.15)
				)
			)
		)
		(property "Public" "False"
			(at 0 0 0)
			(unlocked yes)
			(layer "F.Fab")
			(hide yes)
			(effects
				(font
					(size 1 1)
					(thickness 0.15)
				)
			)
		)
		(sheetname "/Power/")
		(sheetfile "power.kicad_sch")
		(attr smd)
		(fp_line
			(start -0.15 -0.55)
			(end 0.15 -0.55)
			(stroke
				(width 0.15)
				(type solid)
			)
			(layer "F.SilkS")
		)
		(fp_line
			(start -0.15 0.55)
			(end 0.15 0.55)
			(stroke
				(width 0.15)
				(type solid)
			)
			(layer "F.SilkS")
		)
		(fp_rect
			(start -1.25 -0.65)
			(end 1.25 0.65)
			(stroke
				(width 0.05)
				(type solid)
			)
			(fill no)
			(layer "F.CrtYd")
		)
		(fp_rect
			(start -0.8 -0.45)
			(end 0.8 0.45)
			(stroke
				(width 0.15)
				(type solid)
			)
			(fill no)
			(layer "F.Fab")
		)
		(pad "1" smd roundrect
			(at -0.7 0)
			(size 0.8 1.1)
			(layers "F.Cu" "F.Mask" "F.Paste")
			(roundrect_rratio 0.2)
			(net 28 "GND")
			(pintype "passive")
		)
		(pad "2" smd roundrect
			(at 0.7 0)
			(size 0.8 1.1)
			(layers "F.Cu" "F.Mask" "F.Paste")
			(roundrect_rratio 0.2)
			(net 310 "/Power/+1V88_OUT")
			(pintype "passive")
		)
	)
	(footprint "antmicro-footprints:C_0402_1005Metric"
		(layer "F.Cu")
		(at 86.833 63.7)
		(descr "Capacitor SMD 0402")
		(tags "capacitor SMD 0402")
		(property "Reference" "C202"
			(at -1.543 -0.48 0)
			(layer "F.SilkS")
			(effects
				(font
					(size 0.7 0.7)
					(thickness 0.15)
				)
				(justify left bottom)
			)
		)
		(property "Value" "C_100n_0402"
			(at -1.022927 2.155213 0)
			(layer "F.Fab")
			(hide yes)
			(effects
				(font
					(size 0.7 0.7)
					(thickness 0.15)
				)
				(justify left bottom)
			)
		)
		(property "Datasheet" "https://www.murata.com/products/productdetail?partno=GRM155R61H104KE14%23"
			(at 0 0 0)
			(layer "F.Fab")
			(hide yes)
			(effects
				(font
					(size 1.27 1.27)
					(thickness 0.15)
				)
			)
		)
		(property "Description" "SMD Multilayer Ceramic Capacitor, 0.1 µF, 50 V, 0402 [1005 Metric], ± 10%, X5R, GRM Series"
			(at 0 0 0)
			(layer "F.Fab")
			(hide yes)
			(effects
				(font
					(size 1.27 1.27)
					(thickness 0.15)
				)
			)
		)
		(property "MPN" "GRM155R61H104KE14D"
			(at 0 0 0)
			(unlocked yes)
			(layer "F.Fab")
			(hide yes)
			(effects
				(font
					(size 1 1)
					(thickness 0.15)
				)
			)
		)
		(property "Manufacturer" "Murata"
			(at 0 0 0)
			(unlocked yes)
			(layer "F.Fab")
			(hide yes)
			(effects
				(font
					(size 1 1)
					(thickness 0.15)
				)
			)
		)
		(property "License" "Apache-2.0"
			(at 0 0 0)
			(unlocked yes)
			(layer "F.Fab")
			(hide yes)
			(effects
				(font
					(size 1 1)
					(thickness 0.15)
				)
			)
		)
		(property "Author" "Antmicro"
			(at 0 0 0)
			(unlocked yes)
			(layer "F.Fab")
			(hide yes)
			(effects
				(font
					(size 1 1)
					(thickness 0.15)
				)
			)
		)
		(property "Val" "100n"
			(at 0 0 0)
			(unlocked yes)
			(layer "F.Fab")
			(hide yes)
			(effects
				(font
					(size 1 1)
					(thickness 0.15)
				)
			)
		)
		(property "Voltage" "50V"
			(at 0 0 0)
			(unlocked yes)
			(layer "F.Fab")
			(hide yes)
			(effects
				(font
					(size 1 1)
					(thickness 0.15)
				)
			)
		)
		(property "Dielectric" "X5R"
			(at 0 0 0)
			(unlocked yes)
			(layer "F.Fab")
			(hide yes)
			(effects
				(font
					(size 1 1)
					(thickness 0.15)
				)
			)
		)
		(sheetname "/Power/Ideal diode 2/")
		(sheetfile "ideal-diode.kicad_sch")
		(attr smd)
		(fp_rect
			(start -0.925 -0.47)
			(end 0.925 0.47)
			(stroke
				(width 0.05)
				(type default)
			)
			(fill no)
			(layer "F.CrtYd")
		)
		(fp_line
			(start -0.494 -0.25)
			(end 0.504 -0.25)
			(stroke
				(width 0.15)
				(type solid)
			)
			(layer "F.Fab")
		)
		(fp_line
			(start -0.494 0.248)
			(end -0.494 -0.25)
			(stroke
				(width 0.15)
				(type solid)
			)
			(layer "F.Fab")
		)
		(fp_line
			(start 0.504 -0.25)
			(end 0.504 0.248)
			(stroke
				(width 0.15)
				(type solid)
			)
			(layer "F.Fab")
		)
		(fp_line
			(start 0.504 0.248)
			(end -0.494 0.248)
			(stroke
				(width 0.15)
				(type solid)
			)
			(layer "F.Fab")
		)
		(pad "1" smd roundrect
			(at -0.48 0)
			(size 0.59 0.64)
			(layers "F.Cu" "F.Mask" "F.Paste")
			(roundrect_rratio 0.25)
			(net 28 "GND")
			(pintype "passive")
		)
		(pad "2" smd roundrect
			(at 0.48 0)
			(size 0.59 0.64)
			(layers "F.Cu" "F.Mask" "F.Paste")
			(roundrect_rratio 0.25)
			(net 351 "/Power/+5V_USB")
			(pintype "passive")
		)
	)
	(footprint "antmicro-footprints:C_0402_1005Metric"
		(layer "F.Cu")
		(at 115.9 101.100001 180)
		(descr "Capacitor SMD 0402")
		(tags "capacitor SMD 0402")
		(property "Reference" "C210"
			(at -0.82 -0.439999 0)
			(layer "F.SilkS")
			(effects
				(font
					(size 0.7 0.7)
					(thickness 0.15)
				)
				(justify left bottom)
			)
		)
		(property "Value" "C_10n_0402"
			(at -1.022927 2.155213 0)
			(layer "F.Fab")
			(hide yes)
			(effects
				(font
					(size 0.7 0.7)
					(thickness 0.15)
				)
				(justify right top)
			)
		)
		(property "Datasheet" "https://www.murata.com/products/productdetail?partno=GRM155R71H103KA88%23"
			(at 0 0 0)
			(layer "F.Fab")
			(hide yes)
			(effects
				(font
					(size 1.27 1.27)
					(thickness 0.15)
				)
			)
		)
		(property "Description" "SMD Multilayer Ceramic Capacitor, 10000 pF, 50 V, 0402 [1005 Metric], ± 10%, X7R, GRM Series"
			(at 0 0 0)
			(layer "F.Fab")
			(hide yes)
			(effects
				(font
					(size 1.27 1.27)
					(thickness 0.15)
				)
			)
		)
		(property "MPN" "GRM155R71H103KA88D"
			(at 0 0 180)
			(unlocked yes)
			(layer "F.Fab")
			(hide yes)
			(effects
				(font
					(size 1 1)
					(thickness 0.15)
				)
			)
		)
		(property "Manufacturer" "Murata"
			(at 0 0 180)
			(unlocked yes)
			(layer "F.Fab")
			(hide yes)
			(effects
				(font
					(size 1 1)
					(thickness 0.15)
				)
			)
		)
		(property "License" "Apache-2.0"
			(at 0 0 180)
			(unlocked yes)
			(layer "F.Fab")
			(hide yes)
			(effects
				(font
					(size 1 1)
					(thickness 0.15)
				)
			)
		)
		(property "Author" "Antmicro"
			(at 0 0 180)
			(unlocked yes)
			(layer "F.Fab")
			(hide yes)
			(effects
				(font
					(size 1 1)
					(thickness 0.15)
				)
			)
		)
		(property "Val" "10n"
			(at 0 0 180)
			(unlocked yes)
			(layer "F.Fab")
			(hide yes)
			(effects
				(font
					(size 1 1)
					(thickness 0.15)
				)
			)
		)
		(property "Voltage" "50V"
			(at 0 0 180)
			(unlocked yes)
			(layer "F.Fab")
			(hide yes)
			(effects
				(font
					(size 1 1)
					(thickness 0.15)
				)
			)
		)
		(property "Dielectric" "X7R"
			(at 0 0 180)
			(unlocked yes)
			(layer "F.Fab")
			(hide yes)
			(effects
				(font
					(size 1 1)
					(thickness 0.15)
				)
			)
		)
		(sheetname "/Fan controller/")
		(sheetfile "fan-controller.kicad_sch")
		(attr smd exclude_from_pos_files exclude_from_bom dnp)
		(fp_rect
			(start -0.925 -0.47)
			(end 0.925 0.47)
			(stroke
				(width 0.05)
				(type default)
			)
			(fill no)
			(layer "F.CrtYd")
		)
		(fp_line
			(start 0.504 0.248)
			(end -0.494 0.248)
			(stroke
				(width 0.15)
				(type solid)
			)
			(layer "F.Fab")
		)
		(fp_line
			(start 0.504 -0.25)
			(end 0.504 0.248)
			(stroke
				(width 0.15)
				(type solid)
			)
			(layer "F.Fab")
		)
		(fp_line
			(start -0.494 0.248)
			(end -0.494 -0.25)
			(stroke
				(width 0.15)
				(type solid)
			)
			(layer "F.Fab")
		)
		(fp_line
			(start -0.494 -0.25)
			(end 0.504 -0.25)
			(stroke
				(width 0.15)
				(type solid)
			)
			(layer "F.Fab")
		)
		(pad "1" smd roundrect
			(at -0.48 0 180)
			(size 0.59 0.64)
			(layers "F.Cu" "F.Mask" "F.Paste")
			(roundrect_rratio 0.25)
			(net 28 "GND")
			(pintype "passive")
		)
		(pad "2" smd roundrect
			(at 0.48 0 180)
			(size 0.59 0.64)
			(layers "F.Cu" "F.Mask" "F.Paste")
			(roundrect_rratio 0.25)
			(net 386 "Net-(U6-BYPASS)")
			(pintype "passive")
		)
	)
	(footprint "antmicro-footprints:C_0402_1005Metric"
		(layer "F.Cu")
		(at 109.15 106.55 90)
		(descr "Capacitor SMD 0402")
		(tags "capacitor SMD 0402")
		(property "Reference" "C213"
			(at -0.1 -2.6 90)
			(layer "F.SilkS")
			(effects
				(font
					(size 0.7 0.7)
					(thickness 0.15)
				)
				(justify left bottom)
			)
		)
		(property "Value" "C_470p_0402"
			(at -1.022927 2.155213 90)
			(layer "F.Fab")
			(hide yes)
			(effects
				(font
					(size 0.7 0.7)
					(thickness 0.15)
				)
				(justify left bottom)
			)
		)
		(property "Datasheet" "https://www.passivecomponent.com/wp-content/uploads/datasheet/WTC_MLCC_General_Purpose.pdf"
			(at 0 0 90)
			(layer "F.Fab")
			(hide yes)
			(effects
				(font
					(size 1.27 1.27)
					(thickness 0.15)
				)
			)
		)
		(property "Description" "SMD Multilayer Ceramic Capacitor, General Purpose, 470 pF, 25 V, 0402 [1005 Metric], ± 10%, X7R"
			(at 0 0 90)
			(layer "F.Fab")
			(hide yes)
			(effects
				(font
					(size 1.27 1.27)
					(thickness 0.15)
				)
			)
		)
		(property "MPN" "0402B471K250CT"
			(at 0 0 90)
			(unlocked yes)
			(layer "F.Fab")
			(hide yes)
			(effects
				(font
					(size 1 1)
					(thickness 0.15)
				)
			)
		)
		(property "Manufacturer" "Walsin"
			(at 0 0 90)
			(unlocked yes)
			(layer "F.Fab")
			(hide yes)
			(effects
				(font
					(size 1 1)
					(thickness 0.15)
				)
			)
		)
		(property "License" "Apache-2.0"
			(at 0 0 90)
			(unlocked yes)
			(layer "F.Fab")
			(hide yes)
			(effects
				(font
					(size 1 1)
					(thickness 0.15)
				)
			)
		)
		(property "Author" "Antmicro"
			(at 0 0 90)
			(unlocked yes)
			(layer "F.Fab")
			(hide yes)
			(effects
				(font
					(size 1 1)
					(thickness 0.15)
				)
			)
		)
		(property "Val" "470p"
			(at 0 0 90)
			(unlocked yes)
			(layer "F.Fab")
			(hide yes)
			(effects
				(font
					(size 1 1)
					(thickness 0.15)
				)
			)
		)
		(property "Voltage" "25V"
			(at 0 0 90)
			(unlocked yes)
			(layer "F.Fab")
			(hide yes)
			(effects
				(font
					(size 1 1)
					(thickness 0.15)
				)
			)
		)
		(property "Dielectric" "X7R"
			(at 0 0 90)
			(unlocked yes)
			(layer "F.Fab")
			(hide yes)
			(effects
				(font
					(size 1 1)
					(thickness 0.15)
				)
			)
		)
		(sheetname "/Fan controller/")
		(sheetfile "fan-controller.kicad_sch")
		(attr smd exclude_from_pos_files exclude_from_bom dnp)
		(fp_rect
			(start -0.925 -0.47)
			(end 0.925 0.47)
			(stroke
				(width 0.05)
				(type default)
			)
			(fill no)
			(layer "F.CrtYd")
		)
		(fp_line
			(start 0.504 -0.25)
			(end 0.504 0.248)
			(stroke
				(width 0.15)
				(type solid)
			)
			(layer "F.Fab")
		)
		(fp_line
			(start -0.494 -0.25)
			(end 0.504 -0.25)
			(stroke
				(width 0.15)
				(type solid)
			)
			(layer "F.Fab")
		)
		(fp_line
			(start 0.504 0.248)
			(end -0.494 0.248)
			(stroke
				(width 0.15)
				(type solid)
			)
			(layer "F.Fab")
		)
		(fp_line
			(start -0.494 0.248)
			(end -0.494 -0.25)
			(stroke
				(width 0.15)
				(type solid)
			)
			(layer "F.Fab")
		)
		(pad "1" smd roundrect
			(at -0.48 0 90)
			(size 0.59 0.64)
			(layers "F.Cu" "F.Mask" "F.Paste")
			(roundrect_rratio 0.25)
			(net 28 "GND")
			(pintype "passive")
		)
		(pad "2" smd roundrect
			(at 0.48 0 90)
			(size 0.59 0.64)
			(layers "F.Cu" "F.Mask" "F.Paste")
			(roundrect_rratio 0.25)
			(net 387 "/Fan controller/FREQ")
			(pintype "passive")
		)
	)
	(footprint "antmicro-footprints:R_0402_1005Metric"
		(layer "F.Cu")
		(at 54.431 82.764 90)
		(descr "Resistor SMD 0402")
		(tags "resistor SMD 0402")
		(property "Reference" "R54"
			(at -0.926 -0.321 90)
			(layer "F.SilkS")
			(effects
				(font
					(size 0.7 0.7)
					(thickness 0.15)
				)
				(justify left bottom)
			)
		)
		(property "Value" "R_8k2_0402"
			(at -1.011843 1.772046 90)
			(layer "F.Fab")
			(hide yes)
			(effects
				(font
					(size 0.7 0.7)
					(thickness 0.15)
				)
				(justify left bottom)
			)
		)
		(property "Datasheet" "https://www.bourns.com/docs/product-datasheets/cr.pdf"
			(at 0 0 90)
			(layer "F.Fab")
			(hide yes)
			(effects
				(font
					(size 1.27 1.27)
					(thickness 0.15)
				)
			)
		)
		(property "Description" "SMD Chip Resistor"
			(at 0 0 90)
			(layer "F.Fab")
			(hide yes)
			(effects
				(font
					(size 1.27 1.27)
					(thickness 0.15)
				)
			)
		)
		(property "MPN" "CR0402-FX-8201GLF"
			(at 0 0 90)
			(unlocked yes)
			(layer "F.Fab")
			(hide yes)
			(effects
				(font
					(size 1 1)
					(thickness 0.15)
				)
			)
		)
		(property "Manufacturer" "Bourns"
			(at 0 0 90)
			(unlocked yes)
			(layer "F.Fab")
			(hide yes)
			(effects
				(font
					(size 1 1)
					(thickness 0.15)
				)
			)
		)
		(property "License" "Apache-2.0"
			(at 0 0 90)
			(unlocked yes)
			(layer "F.Fab")
			(hide yes)
			(effects
				(font
					(size 1 1)
					(thickness 0.15)
				)
			)
		)
		(property "Author" "Antmicro"
			(at 0 0 90)
			(unlocked yes)
			(layer "F.Fab")
			(hide yes)
			(effects
				(font
					(size 1 1)
					(thickness 0.15)
				)
			)
		)
		(property "Val" "8k2"
			(at 0 0 90)
			(unlocked yes)
			(layer "F.Fab")
			(hide yes)
			(effects
				(font
					(size 1 1)
					(thickness 0.15)
				)
			)
		)
		(property "Tolerance" "1%"
			(at 0 0 90)
			(unlocked yes)
			(layer "F.Fab")
			(hide yes)
			(effects
				(font
					(size 1 1)
					(thickness 0.15)
				)
			)
		)
		(sheetname "/X710-AT2 PCIe/")
		(sheetfile "x710-at2-pcie.kicad_sch")
		(attr smd)
		(fp_rect
			(start -0.925 -0.47)
			(end 0.925 0.47)
			(stroke
				(width 0.05)
				(type default)
			)
			(fill no)
			(layer "F.CrtYd")
		)
		(fp_rect
			(start -0.5 -0.25)
			(end 0.5 0.25)
			(stroke
				(width 0.15)
				(type solid)
			)
			(fill no)
			(layer "F.Fab")
		)
		(pad "1" smd roundrect
			(at -0.48 0 90)
			(size 0.59 0.64)
			(layers "F.Cu" "F.Mask" "F.Paste")
			(roundrect_rratio 0.25)
			(net 28 "GND")
			(pintype "passive")
		)
		(pad "2" smd roundrect
			(at 0.48 0 90)
			(size 0.59 0.64)
			(layers "F.Cu" "F.Mask" "F.Paste")
			(roundrect_rratio 0.25)
			(net 16 "/X710-AT2 PCIe/PCIe_JTAG.JTCK")
			(pintype "passive")
		)
	)
)
